(kicad_pcb
	(version 20260206)
	(generator "pcbnew")
	(generator_version "10.0")
	(general
		(thickness 1.6)
		(legacy_teardrops no)
	)
	(paper "A4")
	(title_block
		(title "04192023_DAF0TMB3IC0_F0TG_MB_C_brd_V02_OCP.brd")
		(comment 1 "Grand Teton / footprints 119-126 of 8354")
	)
	(layers
		(0 "F.Cu" signal "TOP")
		(4 "In1.Cu" signal "GND")
		(6 "In2.Cu" signal "IN1")
		(8 "In3.Cu" signal "GND1")
		(10 "In4.Cu" signal "IN2")
		(12 "In5.Cu" signal "GND2")
		(14 "In6.Cu" signal "IN3")
		(16 "In7.Cu" signal "GND3")
		(18 "In8.Cu" signal "VCC")
		(20 "In9.Cu" signal "VCC1")
		(22 "In10.Cu" signal "GND4")
		(24 "In11.Cu" signal "IN4")
		(26 "In12.Cu" signal "GND5")
		(28 "In13.Cu" signal "IN5")
		(30 "In14.Cu" signal "GND6")
		(32 "In15.Cu" signal "IN6")
		(34 "In16.Cu" signal "GND7")
		(2 "B.Cu" signal "BOTTOM")
		(9 "F.Adhes" user "F.Adhesive")
		(11 "B.Adhes" user "B.Adhesive")
		(13 "F.Paste" user "Package Geometry/Pastemask Top")
		(15 "B.Paste" user "Package Geometry/Pastemask Bottom")
		(5 "F.SilkS" user "Ref Des/Silkscreen Top")
		(7 "B.SilkS" user "Ref Des/Silkscreen Bottom")
		(1 "F.Mask" user "Board Geometry/Soldermask Top")
		(3 "B.Mask" user "Board Geometry/Soldermask Bottom")
		(17 "Dwgs.User" user "User.Drawings")
		(19 "Cmts.User" user "User.Comments")
		(21 "Eco1.User" user "User.Eco1")
		(23 "Eco2.User" user "User.Eco2")
		(25 "Edge.Cuts" user "Board Geometry/Outline")
		(27 "Margin" user)
		(31 "F.CrtYd" user "Package Geometry/Place Bound Top")
		(29 "B.CrtYd" user "Package Geometry/Place Bound Bottom")
		(35 "F.Fab" user "Ref Des/Assembly Top")
		(33 "B.Fab" user "Ref Des/Assembly Bottom")
	)
	(footprint ""
		(layer "F.Cu")
		(at 11.843258 -427.13783 180)
		(property "Reference" "R6162"
			(at 0 0 180)
			(layer "F.SilkS")
			(hide yes)
			(effects
				(font
					(size 1.27 1.27)
				)
			)
		)
		(property "Value" ""
			(at 0 0 180)
			(layer "F.Fab")
			(effects
				(font
					(size 1.27 1.27)
				)
			)
		)
		(duplicate_pad_numbers_are_jumpers no)
		(fp_line
			(start 0.7874 0.4064)
			(end -0.7874 0.4064)
			(stroke
				(width 0.1524)
				(type default)
			)
			(layer "F.SilkS")
		)
		(fp_line
			(start 0.7874 -0.4064)
			(end 0.7874 0.4064)
			(stroke
				(width 0.1524)
				(type default)
			)
			(layer "F.SilkS")
		)
		(fp_line
			(start -0.7874 0.4064)
			(end -0.7874 -0.4064)
			(stroke
				(width 0.1524)
				(type default)
			)
			(layer "F.SilkS")
		)
		(fp_line
			(start -0.7874 -0.4064)
			(end 0.7874 -0.4064)
			(stroke
				(width 0.1524)
				(type default)
			)
			(layer "F.SilkS")
		)
		(fp_line
			(start 0.67945 0.3048)
			(end 0.120396 0.3048)
			(stroke
				(width 0.1)
				(type default)
			)
			(layer "F.Fab")
		)
		(fp_line
			(start 0.67945 -0.3048)
			(end 0.67945 0.3048)
			(stroke
				(width 0.1)
				(type default)
			)
			(layer "F.Fab")
		)
		(fp_line
			(start 0.12065 -0.2794)
			(end 0.12065 -0.3048)
			(stroke
				(width 0.1)
				(type default)
			)
			(layer "F.Fab")
		)
		(fp_line
			(start 0.12065 -0.3048)
			(end 0.67945 -0.3048)
			(stroke
				(width 0.1)
				(type default)
			)
			(layer "F.Fab")
		)
		(fp_line
			(start 0.120396 0.3048)
			(end 0.120396 0.2794)
			(stroke
				(width 0.1)
				(type default)
			)
			(layer "F.Fab")
		)
		(fp_line
			(start 0.120396 0.2794)
			(end -0.12065 0.2794)
			(stroke
				(width 0.1)
				(type default)
			)
			(layer "F.Fab")
		)
		(fp_line
			(start -0.12065 0.3048)
			(end -0.67945 0.3048)
			(stroke
				(width 0.1)
				(type default)
			)
			(layer "F.Fab")
		)
		(fp_line
			(start -0.12065 0.2794)
			(end -0.12065 0.3048)
			(stroke
				(width 0.1)
				(type default)
			)
			(layer "F.Fab")
		)
		(fp_line
			(start -0.12065 -0.2794)
			(end 0.12065 -0.2794)
			(stroke
				(width 0.1)
				(type default)
			)
			(layer "F.Fab")
		)
		(fp_line
			(start -0.12065 -0.305054)
			(end -0.12065 -0.2794)
			(stroke
				(width 0.1)
				(type default)
			)
			(layer "F.Fab")
		)
		(fp_line
			(start -0.67945 0.3048)
			(end -0.67945 -0.305054)
			(stroke
				(width 0.1)
				(type default)
			)
			(layer "F.Fab")
		)
		(fp_line
			(start -0.67945 -0.305054)
			(end -0.12065 -0.305054)
			(stroke
				(width 0.1)
				(type default)
			)
			(layer "F.Fab")
		)
		(pad "1" smd circle
			(at -0.40005 0 180)
			(size 0 0)
			(layers "F.Cu" "F.Mask" "F.Paste")
			(net "FM_P2E_EN2_N")
		)
		(pad "2" smd circle
			(at 0.40005 0 180)
			(size 0 0)
			(layers "F.Cu" "F.Mask" "F.Paste")
			(net "CLK_GEN2_GPU_FPGA_OE_OR_N")
		)
	)
	(footprint ""
		(layer "F.Cu")
		(at 73.201784 -172.974 -90)
		(property "Reference" "PR203"
			(at 0 0 270)
			(layer "F.SilkS")
			(hide yes)
			(effects
				(font
					(size 1.27 1.27)
				)
			)
		)
		(property "Value" ""
			(at 0 0 270)
			(layer "F.Fab")
			(effects
				(font
					(size 1.27 1.27)
				)
			)
		)
		(duplicate_pad_numbers_are_jumpers no)
		(fp_line
			(start -0.7874 0.4064)
			(end -0.7874 -0.4064)
			(stroke
				(width 0.1524)
				(type default)
			)
			(layer "F.SilkS")
		)
		(fp_line
			(start 0.7874 0.4064)
			(end -0.7874 0.4064)
			(stroke
				(width 0.1524)
				(type default)
			)
			(layer "F.SilkS")
		)
		(fp_line
			(start -0.7874 -0.4064)
			(end 0.7874 -0.4064)
			(stroke
				(width 0.1524)
				(type default)
			)
			(layer "F.SilkS")
		)
		(fp_line
			(start 0.7874 -0.4064)
			(end 0.7874 0.4064)
			(stroke
				(width 0.1524)
				(type default)
			)
			(layer "F.SilkS")
		)
		(fp_line
			(start -0.67945 0.3048)
			(end -0.67945 -0.305054)
			(stroke
				(width 0.1)
				(type default)
			)
			(layer "F.Fab")
		)
		(fp_line
			(start -0.12065 0.3048)
			(end -0.67945 0.3048)
			(stroke
				(width 0.1)
				(type default)
			)
			(layer "F.Fab")
		)
		(fp_line
			(start 0.120396 0.3048)
			(end 0.120396 0.2794)
			(stroke
				(width 0.1)
				(type default)
			)
			(layer "F.Fab")
		)
		(fp_line
			(start 0.67945 0.3048)
			(end 0.120396 0.3048)
			(stroke
				(width 0.1)
				(type default)
			)
			(layer "F.Fab")
		)
		(fp_line
			(start -0.12065 0.2794)
			(end -0.12065 0.3048)
			(stroke
				(width 0.1)
				(type default)
			)
			(layer "F.Fab")
		)
		(fp_line
			(start 0.120396 0.2794)
			(end -0.12065 0.2794)
			(stroke
				(width 0.1)
				(type default)
			)
			(layer "F.Fab")
		)
		(fp_line
			(start -0.12065 -0.2794)
			(end 0.12065 -0.2794)
			(stroke
				(width 0.1)
				(type default)
			)
			(layer "F.Fab")
		)
		(fp_line
			(start 0.12065 -0.2794)
			(end 0.12065 -0.3048)
			(stroke
				(width 0.1)
				(type default)
			)
			(layer "F.Fab")
		)
		(fp_line
			(start 0.12065 -0.3048)
			(end 0.67945 -0.3048)
			(stroke
				(width 0.1)
				(type default)
			)
			(layer "F.Fab")
		)
		(fp_line
			(start 0.67945 -0.3048)
			(end 0.67945 0.3048)
			(stroke
				(width 0.1)
				(type default)
			)
			(layer "F.Fab")
		)
		(fp_line
			(start -0.67945 -0.305054)
			(end -0.12065 -0.305054)
			(stroke
				(width 0.1)
				(type default)
			)
			(layer "F.Fab")
		)
		(fp_line
			(start -0.12065 -0.305054)
			(end -0.12065 -0.2794)
			(stroke
				(width 0.1)
				(type default)
			)
			(layer "F.Fab")
		)
		(pad "1" smd circle
			(at -0.40005 0 270)
			(size 0 0)
			(layers "F.Cu" "F.Mask" "F.Paste")
			(net "SW_PVDDCR_CPU0_P1_BOOT5")
		)
		(pad "2" smd circle
			(at 0.40005 0 270)
			(size 0 0)
			(layers "F.Cu" "F.Mask" "F.Paste")
			(net "SW_PVDDCR_CPU0_P1_BOOT5_RC")
		)
	)
	(footprint ""
		(layer "F.Cu")
		(at 42.967402 -375.94286 180)
		(property "Reference" "C835"
			(at 0 0 180)
			(layer "F.SilkS")
			(hide yes)
			(effects
				(font
					(size 1.27 1.27)
				)
			)
		)
		(property "Value" ""
			(at 0 0 180)
			(layer "F.Fab")
			(effects
				(font
					(size 1.27 1.27)
				)
			)
		)
		(duplicate_pad_numbers_are_jumpers no)
		(fp_line
			(start 0.299974 0.150114)
			(end -0.299974 0.150114)
			(stroke
				(width 0.1)
				(type default)
			)
			(layer "F.Fab")
		)
		(fp_line
			(start 0.299974 -0.150114)
			(end 0.299974 0.150114)
			(stroke
				(width 0.1)
				(type default)
			)
			(layer "F.Fab")
		)
		(fp_line
			(start -0.299974 0.150114)
			(end -0.299974 -0.150114)
			(stroke
				(width 0.1)
				(type default)
			)
			(layer "F.Fab")
		)
		(fp_line
			(start -0.299974 -0.150114)
			(end 0.299974 -0.150114)
			(stroke
				(width 0.1)
				(type default)
			)
			(layer "F.Fab")
		)
		(pad "1" smd rect
			(at -0.2667 0 180)
			(size 0.3048 0.381)
			(layers "F.Cu" "F.Mask" "F.Paste")
			(net "P5E_CPU1_P0_TX_C_DP<1>")
		)
		(pad "2" smd rect
			(at 0.2667 0 180)
			(size 0.3048 0.381)
			(layers "F.Cu" "F.Mask" "F.Paste")
			(net "P5E_CPU1_P0_TX_DP<1>")
		)
	)
	(footprint ""
		(layer "F.Cu")
		(at 130.23088 -27.25928 180)
		(property "Reference" "R339"
			(at 0 0 180)
			(layer "F.SilkS")
			(hide yes)
			(effects
				(font
					(size 1.27 1.27)
				)
			)
		)
		(property "Value" ""
			(at 0 0 180)
			(layer "F.Fab")
			(effects
				(font
					(size 1.27 1.27)
				)
			)
		)
		(duplicate_pad_numbers_are_jumpers no)
		(fp_line
			(start 0.32512 0.175006)
			(end -0.32512 0.175006)
			(stroke
				(width 0.1)
				(type default)
			)
			(layer "F.Fab")
		)
		(fp_line
			(start 0.32512 -0.175006)
			(end 0.32512 0.175006)
			(stroke
				(width 0.1)
				(type default)
			)
			(layer "F.Fab")
		)
		(fp_line
			(start -0.32512 0.175006)
			(end -0.32512 -0.175006)
			(stroke
				(width 0.1)
				(type default)
			)
			(layer "F.Fab")
		)
		(fp_line
			(start -0.32512 -0.175006)
			(end 0.32512 -0.175006)
			(stroke
				(width 0.1)
				(type default)
			)
			(layer "F.Fab")
		)
		(pad "1" smd rect
			(at -0.2667 0 180)
			(size 0.3048 0.381)
			(layers "F.Cu" "F.Mask" "F.Paste")
			(net "USB2_CPU0_P0_DP")
		)
		(pad "2" smd rect
			(at 0.2667 0)
			(size 0.3048 0.381)
			(layers "F.Cu" "F.Mask" "F.Paste")
			(net "GND")
		)
	)
	(footprint ""
		(layer "F.Cu")
		(at 473.706444 -353.119436)
		(property "Reference" "DB8"
			(at 1.09601 3.154934 0)
			(unlocked yes)
			(layer "F.SilkS")
			(effects
				(font
					(size 0.7874 0.5842)
					(thickness 0.1524)
				)
				(justify left)
			)
		)
		(property "Value" ""
			(at 0 0 0)
			(layer "F.Fab")
			(effects
				(font
					(size 1.27 1.27)
				)
			)
		)
		(duplicate_pad_numbers_are_jumpers no)
		(fp_line
			(start -3.330702 -4.771136)
			(end 3.330702 -4.771136)
			(stroke
				(width 0.1524)
				(type default)
			)
			(layer "F.SilkS")
		)
		(fp_line
			(start 0 4.011168)
			(end -3.330702 -4.771136)
			(stroke
				(width 0.1524)
				(type default)
			)
			(layer "F.SilkS")
		)
		(fp_line
			(start 2.71653 -3.151378)
			(end 0 4.011168)
			(stroke
				(width 0.1524)
				(type default)
			)
			(layer "F.SilkS")
		)
		(fp_line
			(start -3.330702 -4.771136)
			(end 3.330702 -4.771136)
			(stroke
				(width 0.1)
				(type default)
			)
			(layer "F.Fab")
		)
		(fp_line
			(start 0 4.011168)
			(end -3.330702 -4.771136)
			(stroke
				(width 0.1)
				(type default)
			)
			(layer "F.Fab")
		)
		(fp_line
			(start 3.330702 -4.771136)
			(end 0 4.011168)
			(stroke
				(width 0.1)
				(type default)
			)
			(layer "F.Fab")
		)
		(pad "1" thru_hole circle
			(at 0 0)
			(size 2.159 2.159)
			(drill 1.7018)
			(layers "*.Cu" "*.Mask")
			(remove_unused_layers no)
			(net "T1_GND")
			(clearance 0.0254)
			(thermal_gap 0.0254)
		)
		(pad "2" thru_hole circle
			(at -1.27 -3.348736)
			(size 2.159 2.159)
			(drill 1.7018)
			(layers "*.Cu" "*.Mask")
			(remove_unused_layers no)
			(net "TDR_SE_50_OHM_IN1")
			(clearance 0.0254)
			(thermal_gap 0.0254)
		)
		(pad "3" thru_hole circle
			(at 1.27 -3.348736)
			(size 2.159 2.159)
			(drill 1.7018)
			(layers "*.Cu" "*.Mask")
			(remove_unused_layers no)
			(net "TDR_SE_50_OHM_IN1")
			(clearance 0.0254)
			(thermal_gap 0.0254)
		)
	)
	(footprint ""
		(layer "F.Cu")
		(at 441.89523 -153.774394)
		(property "Reference" "H124"
			(at -3.257296 -7.931912 0)
			(unlocked yes)
			(layer "F.SilkS")
			(effects
				(font
					(size 0.7874 0.5842)
					(thickness 0.1524)
				)
				(justify left)
			)
		)
		(property "Value" ""
			(at 0 0 0)
			(layer "F.Fab")
			(effects
				(font
					(size 1.27 1.27)
				)
			)
		)
		(duplicate_pad_numbers_are_jumpers no)
		(fp_circle
			(center 0 0)
			(end 5.8166 0)
			(stroke
				(width 0.1524)
				(type default)
			)
			(fill no)
			(layer "F.SilkS")
		)
		(fp_circle
			(center 0 0)
			(end 5.8166 0)
			(stroke
				(width 0.1524)
				(type default)
			)
			(fill no)
			(layer "B.SilkS")
		)
		(fp_circle
			(center 0 0)
			(end 5.8166 0)
			(stroke
				(width 0.1)
				(type default)
			)
			(fill no)
			(layer "B.Fab")
		)
		(fp_circle
			(center 0 0)
			(end 5.8166 0)
			(stroke
				(width 0.1)
				(type default)
			)
			(fill no)
			(layer "F.Fab")
		)
		(pad "" np_thru_hole circle
			(at 0 0)
			(size 10.0076 10.0076)
			(drill 10.0076)
			(layers "*.Cu" "*.Mask")
			(clearance 0.381)
			(thermal_gap 0.381)
		)
	)
	(footprint ""
		(layer "F.Cu")
		(at 47.868586 -396.010892)
		(property "Reference" "C247"
			(at 0 0 0)
			(layer "F.SilkS")
			(hide yes)
			(effects
				(font
					(size 1.27 1.27)
				)
			)
		)
		(property "Value" ""
			(at 0 0 0)
			(layer "F.Fab")
			(effects
				(font
					(size 1.27 1.27)
				)
			)
		)
		(duplicate_pad_numbers_are_jumpers no)
		(fp_line
			(start -1.524 -0.762)
			(end 1.524 -0.762)
			(stroke
				(width 0.1524)
				(type default)
			)
			(layer "F.SilkS")
		)
		(fp_line
			(start -1.524 0.762)
			(end -1.524 -0.762)
			(stroke
				(width 0.1524)
				(type default)
			)
			(layer "F.SilkS")
		)
		(fp_line
			(start 1.524 -0.762)
			(end 1.524 0.762)
			(stroke
				(width 0.1524)
				(type default)
			)
			(layer "F.SilkS")
		)
		(fp_line
			(start 1.524 0.762)
			(end -1.524 0.762)
			(stroke
				(width 0.1524)
				(type default)
			)
			(layer "F.SilkS")
		)
		(fp_line
			(start -1.1049 -0.724916)
			(end -1.1049 0.724916)
			(stroke
				(width 0.1)
				(type default)
			)
			(layer "F.Fab")
		)
		(fp_line
			(start -1.1049 0.724916)
			(end 1.1049 0.724916)
			(stroke
				(width 0.1)
				(type default)
			)
			(layer "F.Fab")
		)
		(fp_line
			(start 1.1049 -0.724916)
			(end -1.1049 -0.724916)
			(stroke
				(width 0.1)
				(type default)
			)
			(layer "F.Fab")
		)
		(fp_line
			(start 1.1049 0.724916)
			(end 1.1049 -0.724916)
			(stroke
				(width 0.1)
				(type default)
			)
			(layer "F.Fab")
		)
		(pad "1" smd rect
			(at -0.889 0 180)
			(size 1.016 1.27)
			(layers "F.Cu" "F.Mask" "F.Paste")
			(net "P0V9_CPU1_RT0_2A")
		)
		(pad "2" smd rect
			(at 0.889 0 180)
			(size 1.016 1.27)
			(layers "F.Cu" "F.Mask" "F.Paste")
			(net "GND")
		)
	)
	(footprint ""
		(layer "F.Cu")
		(at 186.055 -137.668 90)
		(property "Reference" "R8032"
			(at 0 0 90)
			(layer "F.SilkS")
			(hide yes)
			(effects
				(font
					(size 1.27 1.27)
				)
			)
		)
		(property "Value" ""
			(at 0 0 90)
			(layer "F.Fab")
			(effects
				(font
					(size 1.27 1.27)
				)
			)
		)
		(duplicate_pad_numbers_are_jumpers no)
		(fp_line
			(start 0.7874 -0.4064)
			(end 0.7874 0.4064)
			(stroke
				(width 0.1524)
				(type default)
			)
			(layer "F.SilkS")
		)
		(fp_line
			(start -0.7874 -0.4064)
			(end 0.7874 -0.4064)
			(stroke
				(width 0.1524)
				(type default)
			)
			(layer "F.SilkS")
		)
		(fp_line
			(start 0.7874 0.4064)
			(end -0.7874 0.4064)
			(stroke
				(width 0.1524)
				(type default)
			)
			(layer "F.SilkS")
		)
		(fp_line
			(start -0.7874 0.4064)
			(end -0.7874 -0.4064)
			(stroke
				(width 0.1524)
				(type default)
			)
			(layer "F.SilkS")
		)
		(fp_line
			(start -0.12065 -0.305054)
			(end -0.12065 -0.2794)
			(stroke
				(width 0.1)
				(type default)
			)
			(layer "F.Fab")
		)
		(fp_line
			(start -0.67945 -0.305054)
			(end -0.12065 -0.305054)
			(stroke
				(width 0.1)
				(type default)
			)
			(layer "F.Fab")
		)
		(fp_line
			(start 0.67945 -0.3048)
			(end 0.67945 0.3048)
			(stroke
				(width 0.1)
				(type default)
			)
			(layer "F.Fab")
		)
		(fp_line
			(start 0.12065 -0.3048)
			(end 0.67945 -0.3048)
			(stroke
				(width 0.1)
				(type default)
			)
			(layer "F.Fab")
		)
		(fp_line
			(start 0.12065 -0.2794)
			(end 0.12065 -0.3048)
			(stroke
				(width 0.1)
				(type default)
			)
			(layer "F.Fab")
		)
		(fp_line
			(start -0.12065 -0.2794)
			(end 0.12065 -0.2794)
			(stroke
				(width 0.1)
				(type default)
			)
			(layer "F.Fab")
		)
		(fp_line
			(start 0.120396 0.2794)
			(end -0.12065 0.2794)
			(stroke
				(width 0.1)
				(type default)
			)
			(layer "F.Fab")
		)
		(fp_line
			(start -0.12065 0.2794)
			(end -0.12065 0.3048)
			(stroke
				(width 0.1)
				(type default)
			)
			(layer "F.Fab")
		)
		(fp_line
			(start 0.67945 0.3048)
			(end 0.120396 0.3048)
			(stroke
				(width 0.1)
				(type default)
			)
			(layer "F.Fab")
		)
		(fp_line
			(start 0.120396 0.3048)
			(end 0.120396 0.2794)
			(stroke
				(width 0.1)
				(type default)
			)
			(layer "F.Fab")
		)
		(fp_line
			(start -0.12065 0.3048)
			(end -0.67945 0.3048)
			(stroke
				(width 0.1)
				(type default)
			)
			(layer "F.Fab")
		)
		(fp_line
			(start -0.67945 0.3048)
			(end -0.67945 -0.305054)
			(stroke
				(width 0.1)
				(type default)
			)
			(layer "F.Fab")
		)
		(pad "1" smd circle
			(at -0.40005 0 90)
			(size 0 0)
			(layers "F.Cu" "F.Mask" "F.Paste")
			(net "FM_ESPI_CPU0_ALERT_SEL")
		)
		(pad "2" smd circle
			(at 0.40005 0 90)
			(size 0 0)
			(layers "F.Cu" "F.Mask" "F.Paste")
			(net "FM_ESPI_CPU0_ALERT_R_SEL")
		)
	)
)
